(kicad_pcb
	(version 20241229)
	(generator "pcbnew")
	(generator_version "9.0")
	(general
		(thickness 1.6296)
		(legacy_teardrops no)
	)
	(paper "A3")
	(title_block
		(title "Thunderbolt to 10GbE adapter")
		(date "2026-04-21")
		(rev "1.1.0")
		(company "Antmicro Ltd")
		(comment 1 "www.antmicro.com")
		(comment 9 "footprints 114-118 of 703")
	)
	(layers
		(0 "F.Cu" signal)
		(4 "In1.Cu" signal)
		(6 "In2.Cu" signal)
		(8 "In3.Cu" signal)
		(10 "In4.Cu" signal)
		(12 "In5.Cu" signal)
		(14 "In6.Cu" signal)
		(2 "B.Cu" signal)
		(9 "F.Adhes" user "F.Adhesive")
		(11 "B.Adhes" user "B.Adhesive")
		(13 "F.Paste" user)
		(15 "B.Paste" user)
		(5 "F.SilkS" user "F.Silkscreen")
		(7 "B.SilkS" user "B.Silkscreen")
		(1 "F.Mask" user)
		(3 "B.Mask" user)
		(17 "Dwgs.User" user "User.Drawings")
		(19 "Cmts.User" user "User.Comments")
		(21 "Eco1.User" user "User.Eco1")
		(23 "Eco2.User" user "User.Eco2")
		(25 "Edge.Cuts" user)
		(27 "Margin" user)
		(31 "F.CrtYd" user "F.Courtyard")
		(29 "B.CrtYd" user "B.Courtyard")
		(35 "F.Fab" user)
		(33 "B.Fab" user)
	)
	(footprint "antmicro-footprints:C_0402_1005Metric"
		(layer "F.Cu")
		(at 132.2 96.4 -90)
		(descr "Capacitor SMD 0402")
		(tags "capacitor SMD 0402")
		(property "Reference" "C114"
			(at -9.299999 -37.414999 270)
			(layer "F.SilkS")
			(effects
				(font
					(size 0.7 0.7)
					(thickness 0.15)
				)
			)
		)
		(property "Value" "C_100n_0402"
			(at -1.022927 2.155213 270)
			(layer "F.Fab")
			(effects
				(font
					(size 0.7 0.7)
					(thickness 0.15)
				)
				(justify left bottom)
			)
		)
		(property "Datasheet" "https://www.murata.com/products/productdetail?partno=GRM155R61H104KE14%23"
			(at 0 0 270)
			(layer "F.Fab")
			(hide yes)
			(effects
				(font
					(size 1.27 1.27)
					(thickness 0.15)
				)
			)
		)
		(property "Description" "SMD Multilayer Ceramic Capacitor, 0.1 µF, 50 V, 0402 [1005 Metric], ± 10%, X5R, GRM Series"
			(at 0 0 270)
			(layer "F.Fab")
			(hide yes)
			(effects
				(font
					(size 1.27 1.27)
					(thickness 0.15)
				)
			)
		)
		(property "MPN" "GRM155R61H104KE14D"
			(at 0 0 270)
			(unlocked yes)
			(layer "F.Fab")
			(hide yes)
			(effects
				(font
					(size 1 1)
					(thickness 0.15)
				)
			)
		)
		(property "Manufacturer" "Murata"
			(at 0 0 270)
			(unlocked yes)
			(layer "F.Fab")
			(hide yes)
			(effects
				(font
					(size 1 1)
					(thickness 0.15)
				)
			)
		)
		(property "License" "Apache-2.0"
			(at 0 0 270)
			(unlocked yes)
			(layer "F.Fab")
			(hide yes)
			(effects
				(font
					(size 1 1)
					(thickness 0.15)
				)
			)
		)
		(property "Author" "Antmicro"
			(at 0 0 270)
			(unlocked yes)
			(layer "F.Fab")
			(hide yes)
			(effects
				(font
					(size 1 1)
					(thickness 0.15)
				)
			)
		)
		(property "Val" "100n"
			(at 0 0 270)
			(unlocked yes)
			(layer "F.Fab")
			(hide yes)
			(effects
				(font
					(size 1 1)
					(thickness 0.15)
				)
			)
		)
		(property "Voltage" "50V"
			(at 0 0 270)
			(unlocked yes)
			(layer "F.Fab")
			(hide yes)
			(effects
				(font
					(size 1 1)
					(thickness 0.15)
				)
			)
		)
		(property "Dielectric" "X5R"
			(at 0 0 270)
			(unlocked yes)
			(layer "F.Fab")
			(hide yes)
			(effects
				(font
					(size 1 1)
					(thickness 0.15)
				)
			)
		)
		(sheetname "/X710 DCDC converters/")
		(sheetfile "DCDC_converters_X710.kicad_sch")
		(attr smd)
		(fp_rect
			(start -0.925 -0.47)
			(end 0.925 0.47)
			(stroke
				(width 0.05)
				(type default)
			)
			(fill no)
			(layer "F.CrtYd")
		)
		(fp_line
			(start -0.494 0.248)
			(end -0.494 -0.25)
			(stroke
				(width 0.15)
				(type solid)
			)
			(layer "F.Fab")
		)
		(fp_line
			(start 0.504 0.248)
			(end -0.494 0.248)
			(stroke
				(width 0.15)
				(type solid)
			)
			(layer "F.Fab")
		)
		(fp_line
			(start -0.494 -0.25)
			(end 0.504 -0.25)
			(stroke
				(width 0.15)
				(type solid)
			)
			(layer "F.Fab")
		)
		(fp_line
			(start 0.504 -0.25)
			(end 0.504 0.248)
			(stroke
				(width 0.15)
				(type solid)
			)
			(layer "F.Fab")
		)
		(fp_text user "License: Apache-2.0"
			(at -0.939 5.799 270)
			(layer "F.Fab")
			(effects
				(font
					(size 0.7 0.7)
					(thickness 0.15)
				)
				(justify left bottom)
			)
		)
		(fp_text user "${REFERENCE}"
			(at -0.939 4.599 270)
			(layer "F.Fab")
			(effects
				(font
					(size 0.7 0.7)
					(thickness 0.15)
				)
				(justify left bottom)
			)
		)
		(fp_text user "Author: Antmicro"
			(at -0.939 3.399 270)
			(layer "F.Fab")
			(effects
				(font
					(size 0.7 0.7)
					(thickness 0.15)
				)
				(justify left bottom)
			)
		)
		(pad "1" smd roundrect
			(at -0.48 0 270)
			(size 0.59 0.64)
			(layers "F.Cu" "F.Mask" "F.Paste")
			(roundrect_rratio 0.25)
			(net 23 "GND")
			(pintype "passive")
		)
		(pad "2" smd roundrect
			(at 0.48 0 270)
			(size 0.59 0.64)
			(layers "F.Cu" "F.Mask" "F.Paste")
			(roundrect_rratio 0.25)
			(net 40 "+5V")
			(pintype "passive")
		)
	)
	(footprint "antmicro-footprints:C_0603_1608Metric_EIA"
		(layer "F.Cu")
		(at 141.704999 99.774999 -90)
		(descr "Capacitor SMD 0603, IPC-7351 Density Level A")
		(tags "Capacitor 0603")
		(property "Reference" "C175"
			(at -9.274999 -35.545001 270)
			(layer "F.SilkS")
			(effects
				(font
					(size 0.7 0.7)
					(thickness 0.15)
				)
			)
		)
		(property "Value" "C_22u_16V_0603"
			(at -1.42757 1.770288 270)
			(layer "F.Fab")
			(effects
				(font
					(size 0.7 0.7)
					(thickness 0.15)
				)
				(justify left bottom)
			)
		)
		(property "Datasheet" "https://product.samsungsem.com/mlcc/CL10A226MO7JZN.do"
			(at 0 0 270)
			(layer "F.Fab")
			(hide yes)
			(effects
				(font
					(size 1.27 1.27)
					(thickness 0.15)
				)
			)
		)
		(property "Description" "SMD Multilayer Ceramic Capacitor"
			(at 0 0 270)
			(layer "F.Fab")
			(hide yes)
			(effects
				(font
					(size 1.27 1.27)
					(thickness 0.15)
				)
			)
		)
		(property "MPN" "CL10A226MO7JZNC"
			(at 0 0 270)
			(unlocked yes)
			(layer "F.Fab")
			(hide yes)
			(effects
				(font
					(size 1 1)
					(thickness 0.15)
				)
			)
		)
		(property "Manufacturer" "Samsung Electro-Mechanics"
			(at 0 0 270)
			(unlocked yes)
			(layer "F.Fab")
			(hide yes)
			(effects
				(font
					(size 1 1)
					(thickness 0.15)
				)
			)
		)
		(property "License" "Apache-2.0"
			(at 0 0 270)
			(unlocked yes)
			(layer "F.Fab")
			(hide yes)
			(effects
				(font
					(size 1 1)
					(thickness 0.15)
				)
			)
		)
		(property "Author" "Antmicro"
			(at 0 0 270)
			(unlocked yes)
			(layer "F.Fab")
			(hide yes)
			(effects
				(font
					(size 1 1)
					(thickness 0.15)
				)
			)
		)
		(property "Val" "22u"
			(at 0 0 270)
			(unlocked yes)
			(layer "F.Fab")
			(hide yes)
			(effects
				(font
					(size 1 1)
					(thickness 0.15)
				)
			)
		)
		(property "Voltage" "16V"
			(at 0 0 270)
			(unlocked yes)
			(layer "F.Fab")
			(hide yes)
			(effects
				(font
					(size 1 1)
					(thickness 0.15)
				)
			)
		)
		(property "Dielectric" ""
			(at 0 0 270)
			(unlocked yes)
			(layer "F.Fab")
			(hide yes)
			(effects
				(font
					(size 1 1)
					(thickness 0.15)
				)
			)
		)
		(sheetname "/X710-AT2 power/")
		(sheetfile "x710-at2-power.kicad_sch")
		(attr smd)
		(fp_line
			(start -0.15 0.55)
			(end 0.15 0.55)
			(stroke
				(width 0.15)
				(type solid)
			)
			(layer "F.SilkS")
		)
		(fp_line
			(start -0.15 -0.55)
			(end 0.15 -0.55)
			(stroke
				(width 0.15)
				(type solid)
			)
			(layer "F.SilkS")
		)
		(fp_rect
			(start -1.25 -0.65)
			(end 1.25 0.65)
			(stroke
				(width 0.05)
				(type solid)
			)
			(fill no)
			(layer "F.CrtYd")
		)
		(fp_rect
			(start -0.8 -0.45)
			(end 0.8 0.45)
			(stroke
				(width 0.15)
				(type solid)
			)
			(fill no)
			(layer "F.Fab")
		)
		(fp_text user "${REFERENCE}"
			(at -1.682 3.895 270)
			(layer "F.Fab")
			(effects
				(font
					(size 0.7 0.7)
					(thickness 0.15)
				)
				(justify left bottom)
			)
		)
		(fp_text user "License: Apache-2.0"
			(at -1.682 5.895 270)
			(layer "F.Fab")
			(effects
				(font
					(size 0.7 0.7)
					(thickness 0.15)
				)
				(justify left bottom)
			)
		)
		(fp_text user "Author: Antmicro"
			(at -1.682 4.894 270)
			(layer "F.Fab")
			(effects
				(font
					(size 0.7 0.7)
					(thickness 0.15)
				)
				(justify left bottom)
			)
		)
		(pad "1" smd roundrect
			(at -0.7 0 270)
			(size 0.8 1.1)
			(layers "F.Cu" "F.Mask" "F.Paste")
			(roundrect_rratio 0.2)
			(net 23 "GND")
			(pintype "passive")
		)
		(pad "2" smd roundrect
			(at 0.7 0 270)
			(size 0.8 1.1)
			(layers "F.Cu" "F.Mask" "F.Paste")
			(roundrect_rratio 0.2)
			(net 6 "DVDD")
			(pintype "passive")
		)
	)
	(footprint "antmicro-footprints:C_0402_1005Metric"
		(layer "F.Cu")
		(at 117.8 121 180)
		(descr "Capacitor SMD 0402")
		(tags "capacitor SMD 0402")
		(property "Reference" "C45"
			(at -0.8 -0.2 180)
			(layer "F.SilkS")
			(effects
				(font
					(size 0.7 0.7)
					(thickness 0.15)
				)
				(justify left bottom)
			)
		)
		(property "Value" "C_220n_0402"
			(at -1.022927 2.155213 180)
			(layer "F.Fab")
			(effects
				(font
					(size 0.7 0.7)
					(thickness 0.15)
				)
				(justify left bottom)
			)
		)
		(property "Datasheet" "https://www.yageo.com/en/Chart/Download/pdf/CC0402KRX5R6BB224"
			(at 0 0 180)
			(layer "F.Fab")
			(hide yes)
			(effects
				(font
					(size 1.27 1.27)
					(thickness 0.15)
				)
			)
		)
		(property "Description" "SMD Multilayer Ceramic Capacitor, 0.22 µF, 10 V, 0402 [1005 Metric], ± 10%, X5R, CC Series"
			(at 0 0 180)
			(layer "F.Fab")
			(hide yes)
			(effects
				(font
					(size 1.27 1.27)
					(thickness 0.15)
				)
			)
		)
		(property "MPN" "CC0402KRX5R6BB224"
			(at 0 0 180)
			(unlocked yes)
			(layer "F.Fab")
			(hide yes)
			(effects
				(font
					(size 1 1)
					(thickness 0.15)
				)
			)
		)
		(property "Manufacturer" "YAGEO"
			(at 0 0 180)
			(unlocked yes)
			(layer "F.Fab")
			(hide yes)
			(effects
				(font
					(size 1 1)
					(thickness 0.15)
				)
			)
		)
		(property "License" "Apache-2.0"
			(at 0 0 180)
			(unlocked yes)
			(layer "F.Fab")
			(hide yes)
			(effects
				(font
					(size 1 1)
					(thickness 0.15)
				)
			)
		)
		(property "Val" "220n"
			(at 0 0 180)
			(unlocked yes)
			(layer "F.Fab")
			(hide yes)
			(effects
				(font
					(size 1 1)
					(thickness 0.15)
				)
			)
		)
		(property "Voltage" ""
			(at 0 0 180)
			(unlocked yes)
			(layer "F.Fab")
			(hide yes)
			(effects
				(font
					(size 1 1)
					(thickness 0.15)
				)
			)
		)
		(property "Dielectric" ""
			(at 0 0 180)
			(unlocked yes)
			(layer "F.Fab")
			(hide yes)
			(effects
				(font
					(size 1 1)
					(thickness 0.15)
				)
			)
		)
		(property "Author" "Antmicro"
			(at 0 0 180)
			(unlocked yes)
			(layer "F.Fab")
			(hide yes)
			(effects
				(font
					(size 1 1)
					(thickness 0.15)
				)
			)
		)
		(sheetname "/TB Controller/")
		(sheetfile "tb.kicad_sch")
		(attr smd)
		(fp_rect
			(start -0.925 -0.47)
			(end 0.925 0.47)
			(stroke
				(width 0.05)
				(type default)
			)
			(fill no)
			(layer "F.CrtYd")
		)
		(fp_line
			(start 0.504 0.248)
			(end -0.494 0.248)
			(stroke
				(width 0.15)
				(type solid)
			)
			(layer "F.Fab")
		)
		(fp_line
			(start 0.504 -0.25)
			(end 0.504 0.248)
			(stroke
				(width 0.15)
				(type solid)
			)
			(layer "F.Fab")
		)
		(fp_line
			(start -0.494 0.248)
			(end -0.494 -0.25)
			(stroke
				(width 0.15)
				(type solid)
			)
			(layer "F.Fab")
		)
		(fp_line
			(start -0.494 -0.25)
			(end 0.504 -0.25)
			(stroke
				(width 0.15)
				(type solid)
			)
			(layer "F.Fab")
		)
		(fp_text user "License: Apache-2.0"
			(at -0.939 5.799 180)
			(layer "F.Fab")
			(effects
				(font
					(size 0.7 0.7)
					(thickness 0.15)
				)
				(justify left bottom)
			)
		)
		(fp_text user "Author: Antmicro"
			(at -0.939 3.399 180)
			(layer "F.Fab")
			(effects
				(font
					(size 0.7 0.7)
					(thickness 0.15)
				)
				(justify left bottom)
			)
		)
		(fp_text user "${REFERENCE}"
			(at -0.939 4.599 180)
			(layer "F.Fab")
			(effects
				(font
					(size 0.7 0.7)
					(thickness 0.15)
				)
				(justify left bottom)
			)
		)
		(pad "1" smd roundrect
			(at -0.48 0 180)
			(size 0.59 0.64)
			(layers "F.Cu" "F.Mask" "F.Paste")
			(roundrect_rratio 0.25)
			(net 325 "/TB Controller/TB_PCIE_TX1_P")
			(pintype "passive")
		)
		(pad "2" smd roundrect
			(at 0.48 0 180)
			(size 0.59 0.64)
			(layers "F.Cu" "F.Mask" "F.Paste")
			(roundrect_rratio 0.25)
			(net 317 "/TB Controller/PCIex4.RX1+")
			(pintype "passive")
		)
	)
	(footprint "antmicro-footprints:C_0805_2012Metric"
		(layer "F.Cu")
		(at 129 140.3)
		(descr "Capacitor SMD 0805")
		(tags "capacitor SMD 0805")
		(property "Reference" "C30"
			(at -1.2 1.8 0)
			(layer "F.SilkS")
			(effects
				(font
					(size 0.7 0.7)
					(thickness 0.15)
				)
				(justify left bottom)
			)
		)
		(property "Value" "C_22u_25V_0805"
			(at -2.055717 1.963152 0)
			(layer "F.Fab")
			(effects
				(font
					(size 0.7 0.7)
					(thickness 0.15)
				)
				(justify left bottom)
			)
		)
		(property "Datasheet" "https://product.samsungsem.com/mlcc/CL21A226MAYNNN.do"
			(at 0 0 0)
			(layer "F.Fab")
			(hide yes)
			(effects
				(font
					(size 1.27 1.27)
					(thickness 0.15)
				)
			)
		)
		(property "Description" "SMT Multilayer Ceramic Capacitor, 22uF, +/-20%, 25V, X5R, 0805 [2012 Metric]"
			(at 0 0 0)
			(layer "F.Fab")
			(hide yes)
			(effects
				(font
					(size 1.27 1.27)
					(thickness 0.15)
				)
			)
		)
		(property "MPN" "CL21A226MAYNNNE"
			(at 0 0 0)
			(unlocked yes)
			(layer "F.Fab")
			(hide yes)
			(effects
				(font
					(size 1 1)
					(thickness 0.15)
				)
			)
		)
		(property "Manufacturer" "Samsung Electro-Mechanics"
			(at 0 0 0)
			(unlocked yes)
			(layer "F.Fab")
			(hide yes)
			(effects
				(font
					(size 1 1)
					(thickness 0.15)
				)
			)
		)
		(property "License" "Apache-2.0"
			(at 0 0 0)
			(unlocked yes)
			(layer "F.Fab")
			(hide yes)
			(effects
				(font
					(size 1 1)
					(thickness 0.15)
				)
			)
		)
		(property "Val" "22u"
			(at 0 0 0)
			(unlocked yes)
			(layer "F.Fab")
			(hide yes)
			(effects
				(font
					(size 1 1)
					(thickness 0.15)
				)
			)
		)
		(property "Voltage" "25V"
			(at 0 0 0)
			(unlocked yes)
			(layer "F.Fab")
			(hide yes)
			(effects
				(font
					(size 1 1)
					(thickness 0.15)
				)
			)
		)
		(property "Dielectric" "X5R"
			(at 0 0 0)
			(unlocked yes)
			(layer "F.Fab")
			(hide yes)
			(effects
				(font
					(size 1 1)
					(thickness 0.15)
				)
			)
		)
		(property "Author" "Antmicro"
			(at 0 0 0)
			(unlocked yes)
			(layer "F.Fab")
			(hide yes)
			(effects
				(font
					(size 1 1)
					(thickness 0.15)
				)
			)
		)
		(property "Public" "False"
			(at 0 0 0)
			(unlocked yes)
			(layer "F.Fab")
			(hide yes)
			(effects
				(font
					(size 1 1)
					(thickness 0.15)
				)
			)
		)
		(sheetname "/PD and TB DC-DC/")
		(sheetfile "PD_and_TB_DC_DC.kicad_sch")
		(attr smd)
		(fp_line
			(start -0.3 -0.7)
			(end 0.3 -0.7)
			(stroke
				(width 0.15)
				(type solid)
			)
			(layer "F.SilkS")
		)
		(fp_line
			(start -0.3 0.7)
			(end 0.3 0.7)
			(stroke
				(width 0.15)
				(type solid)
			)
			(layer "F.SilkS")
		)
		(fp_rect
			(start 1.95 -0.9)
			(end -1.95 0.9)
			(stroke
				(width 0.05)
				(type default)
			)
			(fill no)
			(layer "F.CrtYd")
		)
		(fp_rect
			(start -0.95 -0.675)
			(end 0.95 0.675)
			(stroke
				(width 0.15)
				(type solid)
			)
			(fill no)
			(layer "F.Fab")
		)
		(fp_text user "Author: Antmicro"
			(at -1.9 5.947 0)
			(layer "F.Fab")
			(effects
				(font
					(size 0.7 0.7)
					(thickness 0.15)
				)
				(justify left bottom)
			)
		)
		(fp_text user "License: Apache-2.0"
			(at -1.9 4.947 0)
			(layer "F.Fab")
			(effects
				(font
					(size 0.7 0.7)
					(thickness 0.15)
				)
				(justify left bottom)
			)
		)
		(fp_text user "${REFERENCE}"
			(at -1.9 3.947 0)
			(layer "F.Fab")
			(effects
				(font
					(size 0.7 0.7)
					(thickness 0.15)
				)
				(justify left bottom)
			)
		)
		(pad "1" smd roundrect
			(at -1.1 0)
			(size 1.2 1.3)
			(layers "F.Cu" "F.Mask" "F.Paste")
			(roundrect_rratio 0.25)
			(net 23 "GND")
			(pintype "passive")
		)
		(pad "2" smd roundrect
			(at 1.1 0)
			(size 1.2 1.3)
			(layers "F.Cu" "F.Mask" "F.Paste")
			(roundrect_rratio 0.25)
			(net 182 "VBUS")
			(pintype "passive")
		)
	)
	(footprint "antmicro-footprints:R_0402_1005Metric"
		(layer "F.Cu")
		(at 161 46.3 -90)
		(descr "Resistor SMD 0402")
		(tags "resistor SMD 0402")
		(property "Reference" "R231"
			(at 1.9 -6.3 270)
			(layer "F.SilkS")
			(effects
				(font
					(size 0.7 0.7)
					(thickness 0.15)
				)
				(justify left bottom)
			)
		)
		(property "Value" "R_73k2_0402"
			(at -1.011843 1.772047 270)
			(layer "F.Fab")
			(effects
				(font
					(size 0.7 0.7)
					(thickness 0.15)
				)
				(justify left bottom)
			)
		)
		(property "Datasheet" "https://www.bourns.com/docs/product-datasheets/cr.pdf"
			(at 0 0 270)
			(layer "F.Fab")
			(hide yes)
			(effects
				(font
					(size 1.27 1.27)
					(thickness 0.15)
				)
			)
		)
		(property "Description" "SMD Chip Resistor"
			(at 0 0 270)
			(layer "F.Fab")
			(hide yes)
			(effects
				(font
					(size 1.27 1.27)
					(thickness 0.15)
				)
			)
		)
		(property "MPN" "CR0402-FX-7322GLF"
			(at 0 0 270)
			(unlocked yes)
			(layer "F.Fab")
			(hide yes)
			(effects
				(font
					(size 1 1)
					(thickness 0.15)
				)
			)
		)
		(property "Manufacturer" "Bourns"
			(at 0 0 270)
			(unlocked yes)
			(layer "F.Fab")
			(hide yes)
			(effects
				(font
					(size 1 1)
					(thickness 0.15)
				)
			)
		)
		(property "License" "Apache-2.0"
			(at 0 0 270)
			(unlocked yes)
			(layer "F.Fab")
			(hide yes)
			(effects
				(font
					(size 1 1)
					(thickness 0.15)
				)
			)
		)
		(property "Author" "Antmicro"
			(at 0 0 270)
			(unlocked yes)
			(layer "F.Fab")
			(hide yes)
			(effects
				(font
					(size 1 1)
					(thickness 0.15)
				)
			)
		)
		(property "Val" "73k2"
			(at 0 0 270)
			(unlocked yes)
			(layer "F.Fab")
			(hide yes)
			(effects
				(font
					(size 1 1)
					(thickness 0.15)
				)
			)
		)
		(property "Tolerance" "1%"
			(at 0 0 270)
			(unlocked yes)
			(layer "F.Fab")
			(hide yes)
			(effects
				(font
					(size 1 1)
					(thickness 0.15)
				)
			)
		)
		(sheetname "/Power input/")
		(sheetfile "power_input.kicad_sch")
		(attr smd)
		(fp_rect
			(start -0.925 -0.47)
			(end 0.925 0.47)
			(stroke
				(width 0.05)
				(type default)
			)
			(fill no)
			(layer "F.CrtYd")
		)
		(fp_rect
			(start -0.5 -0.25)
			(end 0.5 0.25)
			(stroke
				(width 0.15)
				(type solid)
			)
			(fill no)
			(layer "F.Fab")
		)
		(fp_text user "${REFERENCE}"
			(at -0.95 3.168 270)
			(layer "F.Fab")
			(effects
				(font
					(size 0.7 0.7)
					(thickness 0.15)
				)
				(justify left bottom)
			)
		)
		(fp_text user "License: Apache-2.0"
			(at -0.95 5.169 270)
			(layer "F.Fab")
			(effects
				(font
					(size 0.7 0.7)
					(thickness 0.15)
				)
				(justify left bottom)
			)
		)
		(fp_text user "Author: Antmicro"
			(at -0.95 4.169 270)
			(layer "F.Fab")
			(effects
				(font
					(size 0.7 0.7)
					(thickness 0.15)
				)
				(justify left bottom)
			)
		)
		(pad "1" smd roundrect
			(at -0.48 0 270)
			(size 0.59 0.64)
			(layers "F.Cu" "F.Mask" "F.Paste")
			(roundrect_rratio 0.25)
			(net 391 "/Power input/5V_FB")
			(pintype "passive")
		)
		(pad "2" smd roundrect
			(at 0.48 0 270)
			(size 0.59 0.64)
			(layers "F.Cu" "F.Mask" "F.Paste")
			(roundrect_rratio 0.25)
			(net 349 "/Power input/5V_OUT")
			(pintype "passive")
		)
	)
)
